# SCM (Grand Teton) — schematic netlist excerpt (pin names and nets, part order shuffled) for the footprints in the layout excerpt that follows; sources: Cadence DE-HDL packaged netlist, KiCad conversion of 12092022_DA0F0TMDCD0_F0T_Management_Board_D_brd_V3_OCP.brd

R624  Q_RES  4.7K 1% CHIP  pkg 0402LF  page 48 : A = P3V3_AUX ; B = FM_BMC_DEBUG_SW_N
R25  Q_RES  150 1% CHIP  pkg 0402LF  page 15 : A = V_DACR_R ; B = GND

(kicad_pcb
	(version 20260206)
	(generator "pcbnew")
	(generator_version "10.0")
	(general
		(thickness 1.6)
		(legacy_teardrops no)
	)
	(paper "A4")
	(title_block
		(title "12092022_DA0F0TMDCD0_F0T_Management_Board_D_brd_V3_OCP.brd")
		(comment 1 "Grand Teton / footprints 479-480 of 1440")
	)
	(layers
		(0 "F.Cu" signal "TOP")
		(4 "In1.Cu" signal "GND")
		(6 "In2.Cu" signal "IN1")
		(8 "In3.Cu" signal "GND1")
		(10 "In4.Cu" signal "IN2")
		(12 "In5.Cu" signal "VCC")
		(14 "In6.Cu" signal "VCC1")
		(16 "In7.Cu" signal "IN3")
		(18 "In8.Cu" signal "GND2")
		(20 "In9.Cu" signal "IN4")
		(22 "In10.Cu" signal "GND3")
		(2 "B.Cu" signal "BOTTOM")
		(9 "F.Adhes" user "F.Adhesive")
		(11 "B.Adhes" user "B.Adhesive")
		(13 "F.Paste" user "Package Geometry/Pastemask Top")
		(15 "B.Paste" user "Package Geometry/Pastemask Bottom")
		(5 "F.SilkS" user "Ref Des/Silkscreen Top")
		(7 "B.SilkS" user "Ref Des/Silkscreen Bottom")
		(1 "F.Mask" user "Board Geometry/Soldermask Top")
		(3 "B.Mask" user "Board Geometry/Soldermask Bottom")
		(17 "Dwgs.User" user "User.Drawings")
		(19 "Cmts.User" user "User.Comments")
		(21 "Eco1.User" user "User.Eco1")
		(23 "Eco2.User" user "User.Eco2")
		(25 "Edge.Cuts" user "Board Geometry/Outline")
		(27 "Margin" user)
		(31 "F.CrtYd" user "Package Geometry/Place Bound Top")
		(29 "B.CrtYd" user "Package Geometry/Place Bound Bottom")
		(35 "F.Fab" user "Ref Des/Assembly Top")
		(33 "B.Fab" user "Ref Des/Assembly Bottom")
	)
	(footprint ""
		(layer "F.Cu")
		(at 61.469016 -79.632556)
		(property "Reference" "R624"
			(at 0 0 0)
			(layer "F.SilkS")
			(hide yes)
			(effects
				(font
					(size 1.27 1.27)
				)
			)
		)
		(property "Value" ""
			(at 0 0 0)
			(layer "F.Fab")
			(effects
				(font
					(size 1.27 1.27)
				)
			)
		)
		(duplicate_pad_numbers_are_jumpers no)
		(fp_line
			(start -0.7874 -0.4064)
			(end 0.7874 -0.4064)
			(stroke
				(width 0.1524)
				(type default)
			)
			(layer "F.SilkS")
		)
		(fp_line
			(start -0.7874 0.4064)
			(end -0.7874 -0.4064)
			(stroke
				(width 0.1524)
				(type default)
			)
			(layer "F.SilkS")
		)
		(fp_line
			(start 0.7874 -0.4064)
			(end 0.7874 0.4064)
			(stroke
				(width 0.1524)
				(type default)
			)
			(layer "F.SilkS")
		)
		(fp_line
			(start 0.7874 0.4064)
			(end -0.7874 0.4064)
			(stroke
				(width 0.1524)
				(type default)
			)
			(layer "F.SilkS")
		)
		(fp_line
			(start -0.67945 -0.305054)
			(end -0.12065 -0.305054)
			(stroke
				(width 0.1)
				(type default)
			)
			(layer "F.Fab")
		)
		(fp_line
			(start -0.67945 0.3048)
			(end -0.67945 -0.305054)
			(stroke
				(width 0.1)
				(type default)
			)
			(layer "F.Fab")
		)
		(fp_line
			(start -0.12065 -0.305054)
			(end -0.12065 -0.2794)
			(stroke
				(width 0.1)
				(type default)
			)
			(layer "F.Fab")
		)
		(fp_line
			(start -0.12065 -0.2794)
			(end 0.12065 -0.2794)
			(stroke
				(width 0.1)
				(type default)
			)
			(layer "F.Fab")
		)
		(fp_line
			(start -0.12065 0.2794)
			(end -0.12065 0.3048)
			(stroke
				(width 0.1)
				(type default)
			)
			(layer "F.Fab")
		)
		(fp_line
			(start -0.12065 0.3048)
			(end -0.67945 0.3048)
			(stroke
				(width 0.1)
				(type default)
			)
			(layer "F.Fab")
		)
		(fp_line
			(start 0.120396 0.2794)
			(end -0.12065 0.2794)
			(stroke
				(width 0.1)
				(type default)
			)
			(layer "F.Fab")
		)
		(fp_line
			(start 0.120396 0.3048)
			(end 0.120396 0.2794)
			(stroke
				(width 0.1)
				(type default)
			)
			(layer "F.Fab")
		)
		(fp_line
			(start 0.12065 -0.3048)
			(end 0.67945 -0.3048)
			(stroke
				(width 0.1)
				(type default)
			)
			(layer "F.Fab")
		)
		(fp_line
			(start 0.12065 -0.2794)
			(end 0.12065 -0.3048)
			(stroke
				(width 0.1)
				(type default)
			)
			(layer "F.Fab")
		)
		(fp_line
			(start 0.67945 -0.3048)
			(end 0.67945 0.3048)
			(stroke
				(width 0.1)
				(type default)
			)
			(layer "F.Fab")
		)
		(fp_line
			(start 0.67945 0.3048)
			(end 0.120396 0.3048)
			(stroke
				(width 0.1)
				(type default)
			)
			(layer "F.Fab")
		)
		(pad "1" smd circle
			(at -0.40005 0)
			(size 0 0)
			(layers "F.Cu" "F.Mask" "F.Paste")
			(net "P3V3_AUX")
		)
		(pad "2" smd circle
			(at 0.40005 0)
			(size 0 0)
			(layers "F.Cu" "F.Mask" "F.Paste")
			(net "FM_BMC_DEBUG_SW_N")
		)
	)
	(footprint ""
		(layer "F.Cu")
		(at 46.586902 -63.934594 -90)
		(property "Reference" "R25"
			(at 0 0 270)
			(layer "F.SilkS")
			(hide yes)
			(effects
				(font
					(size 1.27 1.27)
				)
			)
		)
		(property "Value" ""
			(at 0 0 270)
			(layer "F.Fab")
			(effects
				(font
					(size 1.27 1.27)
				)
			)
		)
		(duplicate_pad_numbers_are_jumpers no)
		(fp_line
			(start -0.7874 0.4064)
			(end -0.7874 -0.4064)
			(stroke
				(width 0.1524)
				(type default)
			)
			(layer "F.SilkS")
		)
		(fp_line
			(start 0.7874 0.4064)
			(end -0.7874 0.4064)
			(stroke
				(width 0.1524)
				(type default)
			)
			(layer "F.SilkS")
		)
		(fp_line
			(start -0.7874 -0.4064)
			(end 0.7874 -0.4064)
			(stroke
				(width 0.1524)
				(type default)
			)
			(layer "F.SilkS")
		)
		(fp_line
			(start 0.7874 -0.4064)
			(end 0.7874 0.4064)
			(stroke
				(width 0.1524)
				(type default)
			)
			(layer "F.SilkS")
		)
		(fp_line
			(start -0.67945 0.3048)
			(end -0.67945 -0.305054)
			(stroke
				(width 0.1)
				(type default)
			)
			(layer "F.Fab")
		)
		(fp_line
			(start -0.12065 0.3048)
			(end -0.67945 0.3048)
			(stroke
				(width 0.1)
				(type default)
			)
			(layer "F.Fab")
		)
		(fp_line
			(start 0.120396 0.3048)
			(end 0.120396 0.2794)
			(stroke
				(width 0.1)
				(type default)
			)
			(layer "F.Fab")
		)
		(fp_line
			(start 0.67945 0.3048)
			(end 0.120396 0.3048)
			(stroke
				(width 0.1)
				(type default)
			)
			(layer "F.Fab")
		)
		(fp_line
			(start -0.12065 0.2794)
			(end -0.12065 0.3048)
			(stroke
				(width 0.1)
				(type default)
			)
			(layer "F.Fab")
		)
		(fp_line
			(start 0.120396 0.2794)
			(end -0.12065 0.2794)
			(stroke
				(width 0.1)
				(type default)
			)
			(layer "F.Fab")
		)
		(fp_line
			(start -0.12065 -0.2794)
			(end 0.12065 -0.2794)
			(stroke
				(width 0.1)
				(type default)
			)
			(layer "F.Fab")
		)
		(fp_line
			(start 0.12065 -0.2794)
			(end 0.12065 -0.3048)
			(stroke
				(width 0.1)
				(type default)
			)
			(layer "F.Fab")
		)
		(fp_line
			(start 0.12065 -0.3048)
			(end 0.67945 -0.3048)
			(stroke
				(width 0.1)
				(type default)
			)
			(layer "F.Fab")
		)
		(fp_line
			(start 0.67945 -0.3048)
			(end 0.67945 0.3048)
			(stroke
				(width 0.1)
				(type default)
			)
			(layer "F.Fab")
		)
		(fp_line
			(start -0.67945 -0.305054)
			(end -0.12065 -0.305054)
			(stroke
				(width 0.1)
				(type default)
			)
			(layer "F.Fab")
		)
		(fp_line
			(start -0.12065 -0.305054)
			(end -0.12065 -0.2794)
			(stroke
				(width 0.1)
				(type default)
			)
			(layer "F.Fab")
		)
		(pad "1" smd circle
			(at -0.40005 0 270)
			(size 0 0)
			(layers "F.Cu" "F.Mask" "F.Paste")
			(net "V_DACR_R")
		)
		(pad "2" smd circle
			(at 0.40005 0 270)
			(size 0 0)
			(layers "F.Cu" "F.Mask" "F.Paste")
			(net "GND")
		)
	)
)
